# T6G (Grand Teton) — schematic netlist excerpt (pin names and nets, part order shuffled) for the footprints in the layout excerpt that follows; sources: Cadence DE-HDL packaged netlist, KiCad conversion of 04192023_DAF0TMB3IC0_F0TG_MB_C_brd_V02_OCP.brd

R8122  Q_RES  5.11K 1% CHIP  pkg 0402LF  page 268 : A = P12V_AUX_UV_TRIGGER ; B = GND

U108  PI3CSW12ZUAEX  IC  pkg UQFN10_0-5_2X1-5  page 159
  \1d+\  = I3C_1_SPD_DDRGL_CPU1_SCL
  \1d-\  = I3C_1_SPD_DDRGL_CPU1_SDA
  \2d+\  = I3C_SCM_3_R_SCL
  \2d-\  = I3C_SCM_3_R_SDA
  GND  = GND
  \oe#\  = FM_I3C_CPU1_MUX1_OE_N
  \d-\  = I3C_SPD_DDRGL_CPU1_LVC1_SDA
  \d+\  = I3C_SPD_DDRGL_CPU1_LVC1_SCL
  S  = FM_I3C_CPU1_MUX1_SEL
  VDD  = P3V3_AUX

(kicad_pcb
	(version 20260206)
	(generator "pcbnew")
	(generator_version "10.0")
	(general
		(thickness 1.6)
		(legacy_teardrops no)
	)
	(paper "A4")
	(title_block
		(title "04192023_DAF0TMB3IC0_F0TG_MB_C_brd_V02_OCP.brd")
		(comment 1 "Grand Teton / footprints 3248-3249 of 8354")
	)
	(layers
		(0 "F.Cu" signal "TOP")
		(4 "In1.Cu" signal "GND")
		(6 "In2.Cu" signal "IN1")
		(8 "In3.Cu" signal "GND1")
		(10 "In4.Cu" signal "IN2")
		(12 "In5.Cu" signal "GND2")
		(14 "In6.Cu" signal "IN3")
		(16 "In7.Cu" signal "GND3")
		(18 "In8.Cu" signal "VCC")
		(20 "In9.Cu" signal "VCC1")
		(22 "In10.Cu" signal "GND4")
		(24 "In11.Cu" signal "IN4")
		(26 "In12.Cu" signal "GND5")
		(28 "In13.Cu" signal "IN5")
		(30 "In14.Cu" signal "GND6")
		(32 "In15.Cu" signal "IN6")
		(34 "In16.Cu" signal "GND7")
		(2 "B.Cu" signal "BOTTOM")
		(9 "F.Adhes" user "F.Adhesive")
		(11 "B.Adhes" user "B.Adhesive")
		(13 "F.Paste" user "Package Geometry/Pastemask Top")
		(15 "B.Paste" user "Package Geometry/Pastemask Bottom")
		(5 "F.SilkS" user "Ref Des/Silkscreen Top")
		(7 "B.SilkS" user "Ref Des/Silkscreen Bottom")
		(1 "F.Mask" user "Board Geometry/Soldermask Top")
		(3 "B.Mask" user "Board Geometry/Soldermask Bottom")
		(17 "Dwgs.User" user "User.Drawings")
		(19 "Cmts.User" user "User.Comments")
		(21 "Eco1.User" user "User.Eco1")
		(23 "Eco2.User" user "User.Eco2")
		(25 "Edge.Cuts" user "Board Geometry/Outline")
		(27 "Margin" user)
		(31 "F.CrtYd" user "Package Geometry/Place Bound Top")
		(29 "B.CrtYd" user "Package Geometry/Place Bound Bottom")
		(35 "F.Fab" user "Ref Des/Assembly Top")
		(33 "B.Fab" user "Ref Des/Assembly Bottom")
	)
	(footprint ""
		(layer "F.Cu")
		(at 182.912766 -164.761418 90)
		(property "Reference" "U108"
			(at 0.488188 3.023108 90)
			(unlocked yes)
			(layer "F.SilkS")
			(effects
				(font
					(size 0.7874 0.5842)
					(thickness 0.1524)
				)
			)
		)
		(property "Value" ""
			(at 0 0 90)
			(layer "F.Fab")
			(effects
				(font
					(size 1.27 1.27)
				)
			)
		)
		(duplicate_pad_numbers_are_jumpers no)
		(fp_line
			(start 1.03378 -1.284478)
			(end 1.03378 1.284478)
			(stroke
				(width 0.1524)
				(type default)
			)
			(layer "F.SilkS")
		)
		(fp_line
			(start -1.03378 -1.284478)
			(end 1.03378 -1.284478)
			(stroke
				(width 0.1524)
				(type default)
			)
			(layer "F.SilkS")
		)
		(fp_line
			(start 1.03378 1.284478)
			(end -1.03378 1.284478)
			(stroke
				(width 0.1524)
				(type default)
			)
			(layer "F.SilkS")
		)
		(fp_line
			(start -1.03378 1.284478)
			(end -1.03378 -1.284478)
			(stroke
				(width 0.1524)
				(type default)
			)
			(layer "F.SilkS")
		)
		(fp_poly
			(pts
				(xy -1.806702 -1.052576) (xy -1.201674 -0.750062) (xy -1.806702 -0.447548)
			)
			(stroke
				(width 0)
				(type default)
			)
			(fill yes)
			(layer "F.SilkS")
		)
		(fp_line
			(start 0.774954 -1.02489)
			(end 0.774954 1.02489)
			(stroke
				(width 0.1)
				(type default)
			)
			(layer "F.Fab")
		)
		(fp_line
			(start -0.774954 -1.02489)
			(end 0.774954 -1.02489)
			(stroke
				(width 0.1)
				(type default)
			)
			(layer "F.Fab")
		)
		(fp_line
			(start 0.774954 1.02489)
			(end -0.774954 1.02489)
			(stroke
				(width 0.1)
				(type default)
			)
			(layer "F.Fab")
		)
		(fp_line
			(start -0.774954 1.02489)
			(end -0.774954 -1.02489)
			(stroke
				(width 0.1)
				(type default)
			)
			(layer "F.Fab")
		)
		(fp_poly
			(pts
				(xy -1.201674 -0.750062) (xy -1.806702 -0.447548) (xy -1.806702 -1.052576)
			)
			(stroke
				(width 0)
				(type default)
			)
			(fill yes)
			(layer "F.Fab")
		)
		(pad "1" smd rect
			(at -0.64008 -0.750062 180)
			(size 0.3048 0.5334)
			(layers "F.Cu" "F.Mask" "F.Paste")
			(net "I3C_1_SPD_DDRGL_CPU1_SCL")
		)
		(pad "2" smd rect
			(at -0.64008 -0.249936 180)
			(size 0.254 0.5334)
			(layers "F.Cu" "F.Mask" "F.Paste")
			(net "I3C_1_SPD_DDRGL_CPU1_SDA")
		)
		(pad "3" smd rect
			(at -0.64008 0.249936 180)
			(size 0.254 0.5334)
			(layers "F.Cu" "F.Mask" "F.Paste")
			(net "I3C_SCM_3_R_SCL")
		)
		(pad "4" smd rect
			(at -0.64008 0.750062 180)
			(size 0.3048 0.5334)
			(layers "F.Cu" "F.Mask" "F.Paste")
			(net "I3C_SCM_3_R_SDA")
		)
		(pad "5" smd rect
			(at 0 0.839978 90)
			(size 0.3302 0.635)
			(layers "F.Cu" "F.Mask" "F.Paste")
			(net "GND")
		)
		(pad "6" smd rect
			(at 0.64008 0.750062 180)
			(size 0.3048 0.5334)
			(layers "F.Cu" "F.Mask" "F.Paste")
			(net "FM_I3C_CPU1_MUX1_OE_N")
		)
		(pad "7" smd rect
			(at 0.64008 0.249936 180)
			(size 0.254 0.5334)
			(layers "F.Cu" "F.Mask" "F.Paste")
			(net "I3C_SPD_DDRGL_CPU1_LVC1_SDA")
		)
		(pad "8" smd rect
			(at 0.64008 -0.249936 180)
			(size 0.254 0.5334)
			(layers "F.Cu" "F.Mask" "F.Paste")
			(net "I3C_SPD_DDRGL_CPU1_LVC1_SCL")
		)
		(pad "9" smd rect
			(at 0.64008 -0.750062 180)
			(size 0.3048 0.5334)
			(layers "F.Cu" "F.Mask" "F.Paste")
			(net "FM_I3C_CPU1_MUX1_SEL")
		)
		(pad "10" smd rect
			(at 0 -0.839978 90)
			(size 0.3302 0.635)
			(layers "F.Cu" "F.Mask" "F.Paste")
			(net "P3V3_AUX")
		)
	)
	(footprint ""
		(layer "F.Cu")
		(at 145.669 -117.348)
		(property "Reference" "R8122"
			(at 0 0 0)
			(layer "F.SilkS")
			(hide yes)
			(effects
				(font
					(size 1.27 1.27)
				)
			)
		)
		(property "Value" ""
			(at 0 0 0)
			(layer "F.Fab")
			(effects
				(font
					(size 1.27 1.27)
				)
			)
		)
		(duplicate_pad_numbers_are_jumpers no)
		(fp_line
			(start -0.7874 -0.4064)
			(end 0.7874 -0.4064)
			(stroke
				(width 0.1524)
				(type default)
			)
			(layer "F.SilkS")
		)
		(fp_line
			(start -0.7874 0.4064)
			(end -0.7874 -0.4064)
			(stroke
				(width 0.1524)
				(type default)
			)
			(layer "F.SilkS")
		)
		(fp_line
			(start 0.7874 -0.4064)
			(end 0.7874 0.4064)
			(stroke
				(width 0.1524)
				(type default)
			)
			(layer "F.SilkS")
		)
		(fp_line
			(start 0.7874 0.4064)
			(end -0.7874 0.4064)
			(stroke
				(width 0.1524)
				(type default)
			)
			(layer "F.SilkS")
		)
		(fp_line
			(start -0.67945 -0.305054)
			(end -0.12065 -0.305054)
			(stroke
				(width 0.1)
				(type default)
			)
			(layer "F.Fab")
		)
		(fp_line
			(start -0.67945 0.3048)
			(end -0.67945 -0.305054)
			(stroke
				(width 0.1)
				(type default)
			)
			(layer "F.Fab")
		)
		(fp_line
			(start -0.12065 -0.305054)
			(end -0.12065 -0.2794)
			(stroke
				(width 0.1)
				(type default)
			)
			(layer "F.Fab")
		)
		(fp_line
			(start -0.12065 -0.2794)
			(end 0.12065 -0.2794)
			(stroke
				(width 0.1)
				(type default)
			)
			(layer "F.Fab")
		)
		(fp_line
			(start -0.12065 0.2794)
			(end -0.12065 0.3048)
			(stroke
				(width 0.1)
				(type default)
			)
			(layer "F.Fab")
		)
		(fp_line
			(start -0.12065 0.3048)
			(end -0.67945 0.3048)
			(stroke
				(width 0.1)
				(type default)
			)
			(layer "F.Fab")
		)
		(fp_line
			(start 0.120396 0.2794)
			(end -0.12065 0.2794)
			(stroke
				(width 0.1)
				(type default)
			)
			(layer "F.Fab")
		)
		(fp_line
			(start 0.120396 0.3048)
			(end 0.120396 0.2794)
			(stroke
				(width 0.1)
				(type default)
			)
			(layer "F.Fab")
		)
		(fp_line
			(start 0.12065 -0.3048)
			(end 0.67945 -0.3048)
			(stroke
				(width 0.1)
				(type default)
			)
			(layer "F.Fab")
		)
		(fp_line
			(start 0.12065 -0.2794)
			(end 0.12065 -0.3048)
			(stroke
				(width 0.1)
				(type default)
			)
			(layer "F.Fab")
		)
		(fp_line
			(start 0.67945 -0.3048)
			(end 0.67945 0.3048)
			(stroke
				(width 0.1)
				(type default)
			)
			(layer "F.Fab")
		)
		(fp_line
			(start 0.67945 0.3048)
			(end 0.120396 0.3048)
			(stroke
				(width 0.1)
				(type default)
			)
			(layer "F.Fab")
		)
		(pad "1" smd circle
			(at -0.40005 0)
			(size 0 0)
			(layers "F.Cu" "F.Mask" "F.Paste")
			(net "P12V_AUX_UV_TRIGGER")
		)
		(pad "2" smd circle
			(at 0.40005 0)
			(size 0 0)
			(layers "F.Cu" "F.Mask" "F.Paste")
			(net "GND")
		)
	)
)
